# S9S_MB_2U (Grand Teton) — schematic netlist excerpt (pin names and nets, part order shuffled) for the footprints in the layout excerpt that follows; sources: Cadence DE-HDL packaged netlist, KiCad conversion of 03242023_DA0F0TMBIJ0_F0T_Motherboard_J_brd_V01_OCP.brd

J8  SCONN288_ADR50017P087CC  SCONN288_ADR50017-P087CC IO  pkg DDR288S_1-1VXB  page 89
  VIN_BULK0  = P12V_S3_AUX_CPU0_NVDIMM
  RFU0  = TP_CHD_CPU0_DIMM2_FRU_0
  VIN_MGMT  = P3V3_AUX
  HSCL  = I3C_SPD_DDRABCD_CPU0_LVC1_SCL_7
  HSDA  = I3C_SPD_DDRABCD_CPU0_LVC1_SDA
  VSS0  = GND
  DQ0_A  = M_D_CPU0_SA_DQ<0>
  VSS1  = GND
  DQ1_A  = M_D_CPU0_SA_DQ<1>
  VSS2  = GND
  DQS0_A_T  = M_D_CPU0_SA_DQS_DP<0>
  DQS0_A_C  = M_D_CPU0_SA_DQS_DN<0>
  VSS3  = GND
  DQ4_A  = M_D_CPU0_SA_DQ<4>
  VSS4  = GND
  DQ5_A  = M_D_CPU0_SA_DQ<5>
  VSS5  = GND
  DQ8_A  = M_D_CPU0_SA_DQ<8>
  VSS6  = GND
  DQ9_A  = M_D_CPU0_SA_DQ<9>
  VSS7  = GND
  DQS1_A_T  = M_D_CPU0_SA_DQS_DP<1>
  DQS1_A_C  = M_D_CPU0_SA_DQS_DN<1>
  VSS8  = GND
  DQ12_A  = M_D_CPU0_SA_DQ<12>
  VSS9  = GND
  DQ13_A  = M_D_CPU0_SA_DQ<13>
  VSS10  = GND
  DQ16_A  = M_D_CPU0_SA_DQ<16>
  VSS11  = GND
  DQ17_A  = M_D_CPU0_SA_DQ<17>
  VSS12  = GND
  DQS2_A_T  = M_D_CPU0_SA_DQS_DP<2>
  DQS2_A_C  = M_D_CPU0_SA_DQS_DN<2>
  VSS13  = GND
  DQ20_A  = M_D_CPU0_SA_DQ<20>
  VSS14  = GND
  DQ21_A  = M_D_CPU0_SA_DQ<21>
  VSS15  = GND
  DQ24_A  = M_D_CPU0_SA_DQ<24>
  VSS16  = GND
  DQ25_A  = M_D_CPU0_SA_DQ<25>
  VSS17  = GND
  DQS3_A_T  = M_D_CPU0_SA_DQS_DP<3>
  DQS3_A_C  = M_D_CPU0_SA_DQS_DN<3>
  VSS18  = GND
  DQ28_A  = M_D_CPU0_SA_DQ<28>
  VSS19  = GND
  DQ29_A  = M_D_CPU0_SA_DQ<29>
  VSS20  = GND
  CB0_A  = M_D_CPU0_SA_CB<0>
  VSS21  = GND
  CB1_A  = M_D_CPU0_SA_CB<1>
  VSS22  = GND
  DQS4_A_T  = M_D_CPU0_SA_DQS_DP<4>
  DQS4_A_C  = M_D_CPU0_SA_DQS_DN<4>
  VSS23  = GND
  CB4_A  = M_D_CPU0_SA_CB<4>
  VSS24  = GND
  CB5_A  = M_D_CPU0_SA_CB<5>
  VSS25  = GND
  ALERT_N  = M_D_CPU0_ALERT_N
  VSS26  = GND
  CS0_A_N  = M_D_CPU0_SA_CS_N<2>
  VSS27  = GND
  CA0_A  = M_D_CPU0_SA_CA<0>
  VSS28  = GND
  CA2_A  = M_D_CPU0_SA_CA<2>
  VSS29  = GND
  CA4_A  = M_D_CPU0_SA_CA<4>
  VSS30  = GND
  CA6_A  = M_D_CPU0_SA_CA<6>
  VSS31  = GND
  PAR_A  = M_D_CPU0_SA_PAR
  VSS32  = GND
  CA0_B  = M_D_CPU0_SB_CA<0>
  VSS33  = GND
  CA2_B  = M_D_CPU0_SB_CA<2>
  VSS34  = GND
  CA4_B  = M_D_CPU0_SB_CA<4>
  VSS35  = GND
  CA6_B  = M_D_CPU0_SB_CA<6>
  VSS36  = GND
  CS0_B_N  = M_D_CPU0_SB_CS_N<2>
  VSS37  = GND
  \lbd||rsp_a_n\  = M_D_CPU0_SA_RSP<1>
  \lbs||rsp_b_n\  = M_D_CPU0_SB_RSP<1>
  VSS38  = GND
  CB4_B  = M_D_CPU0_SB_CB<4>
  VSS39  = GND
  CB5_B  = M_D_CPU0_SB_CB<5>
  VSS40  = GND
  \dqs9_b_t||tdqs9_b_t||dbi4_b_n\  = M_D_CPU0_SB_DQS_DP<9>
  \dqs9_b_c||tdqs9_b_c\  = M_D_CPU0_SB_DQS_DN<9>
  VSS41  = GND
  CB0_B  = M_D_CPU0_SB_CB<0>
  VSS42  = GND
  CB1_B  = M_D_CPU0_SB_CB<1>
  VSS43  = GND
  DQ0_B  = M_D_CPU0_SB_DQ<0>
  VSS44  = GND
  DQ1_B  = M_D_CPU0_SB_DQ<1>
  VSS45  = GND
  DQS0_B_T  = M_D_CPU0_SB_DQS_DP<0>
  DQS0_B_C  = M_D_CPU0_SB_DQS_DN<0>
  VSS46  = GND
  DQ4_B  = M_D_CPU0_SB_DQ<4>
  VSS47  = GND
  DQ5_B  = M_D_CPU0_SB_DQ<5>
  VSS48  = GND
  DQ8_B  = M_D_CPU0_SB_DQ<8>
  VSS49  = GND
  DQ9_B  = M_D_CPU0_SB_DQ<9>
  VSS50  = GND
  DQS1_B_T  = M_D_CPU0_SB_DQS_DP<1>
  DQS1_B_C  = M_D_CPU0_SB_DQS_DN<1>
  VSS51  = GND
  DQ12_B  = M_D_CPU0_SB_DQ<12>
  VSS52  = GND
  DQ13_B  = M_D_CPU0_SB_DQ<13>
  VSS53  = GND
  DQ16_B  = M_D_CPU0_SB_DQ<16>
  VSS54  = GND
  DQ17_B  = M_D_CPU0_SB_DQ<17>
  VSS55  = GND
  DQS2_B_T  = M_D_CPU0_SB_DQS_DP<2>
  DQS2_B_C  = M_D_CPU0_SB_DQS_DN<2>
  VSS56  = GND
  DQ20_B  = M_D_CPU0_SB_DQ<20>
  VSS57  = GND
  DQ21_B  = M_D_CPU0_SB_DQ<21>
  VSS58  = GND
  DQ24_B  = M_D_CPU0_SB_DQ<24>
  VSS59  = GND
  DQ25_B  = M_D_CPU0_SB_DQ<25>
  VSS60  = GND
  DQS3_B_T  = M_D_CPU0_SB_DQS_DP<3>
  DQS3_B_C  = M_D_CPU0_SB_DQS_DN<3>
  VSS61  = GND
  DQ28_B  = M_D_CPU0_SB_DQ<28>
  VSS62  = GND
  DQ29_B  = M_D_CPU0_SB_DQ<29>
  VSS63  = GND
  RFU1  = TP_CHD_CPU0_DIMM2_FRU_1
  VIN_BULK1  = P12V_S3_AUX_CPU0_NVDIMM
  VIN_BULK2  = P12V_S3_AUX_CPU0_NVDIMM
  \pwr_good||fail_n\  = PWRGD_CHD_CPU0_DIMM2
  HSA  = PD_CHD_CPU0_DIMM2_SAA
  RFU2  = TP_CHD_CPU0_DIMM2_FRU_2
  RFU3  = TP_CHD_CPU0_DIMM2_FRU_3
  VSS64  = GND
  DQ2_A  = M_D_CPU0_SA_DQ<2>
  VSS65  = GND
  DQ3_A  = M_D_CPU0_SA_DQ<3>
  VSS66  = GND
  \dqs5_a_c||tdqs5_a_c||dqs5_a_t||tdqs5_a_t\  = M_D_CPU0_SA_DQS_DN<5>
  \dqs5_a_t||tdqs5_a_t\  = M_D_CPU0_SA_DQS_DP<5>
  VSS67  = GND
  DQ6_A  = M_D_CPU0_SA_DQ<6>
  VSS68  = GND
  DQ7_A  = M_D_CPU0_SA_DQ<7>
  VSS69  = GND
  DQ10_A  = M_D_CPU0_SA_DQ<10>
  VSS70  = GND
  DQ11_A  = M_D_CPU0_SA_DQ<11>
  VSS71  = GND
  \dqs6_a_c||tdqs6_a_c||dqs6_a_t||tdqs6_a_t\  = M_D_CPU0_SA_DQS_DN<6>
  \dqs6_a_t||tdqs6_a_t\  = M_D_CPU0_SA_DQS_DP<6>
  VSS72  = GND
  DQ14_A  = M_D_CPU0_SA_DQ<14>
  VSS73  = GND
  DQ15_A  = M_D_CPU0_SA_DQ<15>
  VSS74  = GND
  DQ18_A  = M_D_CPU0_SA_DQ<18>
  VSS75  = GND
  DQ19_A  = M_D_CPU0_SA_DQ<19>
  VSS76  = GND
  \dqs7_a_c||tdqs7_a_c\  = M_D_CPU0_SA_DQS_DN<7>
  \dqs7_a_t||tdqs7_a_t\  = M_D_CPU0_SA_DQS_DP<7>
  VSS77  = GND
  DQ22_A  = M_D_CPU0_SA_DQ<22>
  VSS78  = GND
  DQ23_A  = M_D_CPU0_SA_DQ<23>
  VSS79  = GND
  DQ26_A  = M_D_CPU0_SA_DQ<26>
  VSS80  = GND
  DQ27_A  = M_D_CPU0_SA_DQ<27>
  VSS81  = GND
  \dqs8_a_c||tdqs8_a_c\  = M_D_CPU0_SA_DQS_DN<8>
  \dqs8_a_t||tdqs8_a_t\  = M_D_CPU0_SA_DQS_DP<8>
  VSS82  = GND
  DQ30_A  = M_D_CPU0_SA_DQ<30>
  VSS83  = GND
  DQ31_A  = M_D_CPU0_SA_DQ<31>
  VSS84  = GND
  CB2_A  = M_D_CPU0_SA_CB<2>
  VSS85  = GND
  CB3_A  = M_D_CPU0_SA_CB<3>
  VSS86  = GND
  \dqs9_a_c||tdqs9_a_c\  = M_D_CPU0_SA_DQS_DN<9>
  \dqs9_a_t||tdqs9_a_t\  = M_D_CPU0_SA_DQS_DP<9>
  VSS87  = GND
  CB6_A  = M_D_CPU0_SA_CB<6>
  VSS88  = GND
  CB7_A  = M_D_CPU0_SA_CB<7>
  VSS89  = GND
  RESET_N  = RST_M_CD_CPU0_FPGA_N
  VSS90  = GND
  CS1_A_N  = M_D_CPU0_SA_CS_N<3>
  VSS91  = GND
  CA1_A  = M_D_CPU0_SA_CA<1>
  VSS92  = GND
  CA3_A  = M_D_CPU0_SA_CA<3>
  VSS93  = GND
  CA5_A  = M_D_CPU0_SA_CA<5>
  VSS94  = GND
  CK_T  = M_D_CPU0_CLK_DP<1>
  CK_C  = M_D_CPU0_CLK_DN<1>
  VSS95  = GND
  RFU4  = TP_CHD_CPU0_DIMM2_FRU_4
  CA1_B  = M_D_CPU0_SB_CA<1>
  VSS96  = GND
  CA3_B  = M_D_CPU0_SB_CA<3>
  VSS97  = GND
  CA5_B  = M_D_CPU0_SB_CA<5>
  VSS98  = GND
  PAR_B  = M_D_CPU0_SB_PAR
  VSS99  = GND
  CS1_B_N  = M_D_CPU0_SB_CS_N<3>
  VSS100  = GND
  RFU5  = TP_CHD_CPU0_DIMM2_FRU_5
  RFU6  = TP_CHD_CPU0_DIMM2_FRU_6
  VSS101  = GND
  CB6_B  = M_D_CPU0_SB_CB<6>
  VSS102  = GND
  CB7_B  = M_D_CPU0_SB_CB<7>
  VSS103  = GND
  DQS4_B_C  = M_D_CPU0_SB_DQS_DN<4>
  DQS4_B_T  = M_D_CPU0_SB_DQS_DP<4>
  VSS104  = GND
  CB2_B  = M_D_CPU0_SB_CB<2>
  VSS105  = GND
  CB3_B  = M_D_CPU0_SB_CB<3>
  VSS106  = GND
  DQ2_B  = M_D_CPU0_SB_DQ<2>
  VSS107  = GND
  DQ3_B  = M_D_CPU0_SB_DQ<3>
  VSS108  = GND
  \dqs5_b_c||tdqs5_b_c\  = M_D_CPU0_SB_DQS_DN<5>
  \dqs5_b_t||tdqs5_b_t\  = M_D_CPU0_SB_DQS_DP<5>
  VSS109  = GND
  DQ6_B  = M_D_CPU0_SB_DQ<6>
  VSS110  = GND
  DQ7_B  = M_D_CPU0_SB_DQ<7>
  VSS111  = GND
  DQ10_B  = M_D_CPU0_SB_DQ<10>
  VSS112  = GND
  DQ11_B  = M_D_CPU0_SB_DQ<11>
  VSS113  = GND
  \dqs6_b_c||tdqs6_b_c\  = M_D_CPU0_SB_DQS_DN<6>
  \dqs6_b_t||tdqs6_b_t\  = M_D_CPU0_SB_DQS_DP<6>
  VSS114  = GND
  DQ14_B  = M_D_CPU0_SB_DQ<14>
  VSS115  = GND
  DQ15_B  = M_D_CPU0_SB_DQ<15>
  VSS116  = GND
  DQ18_B  = M_D_CPU0_SB_DQ<18>
  VSS117  = GND
  DQ19_B  = M_D_CPU0_SB_DQ<19>
  VSS118  = GND
  \dqs7_b_c||tdqs7_b_c\  = M_D_CPU0_SB_DQS_DN<7>
  \dqs7_b_t||tdqs7_b_t\  = M_D_CPU0_SB_DQS_DP<7>
  VSS119  = GND
  DQ22_B  = M_D_CPU0_SB_DQ<22>
  VSS120  = GND
  DQ23_B  = M_D_CPU0_SB_DQ<23>
  VSS121  = GND
  DQ26_B  = M_D_CPU0_SB_DQ<26>
  VSS122  = GND
  DQ27_B  = M_D_CPU0_SB_DQ<27>
  VSS123  = GND
  \dqs8_b_c||tdqs8_b_c\  = M_D_CPU0_SB_DQS_DN<8>
  \dqs8_b_t||tdqs8_b_t\  = M_D_CPU0_SB_DQS_DP<8>
  VSS124  = GND
  DQ30_B  = M_D_CPU0_SB_DQ<30>
  VSS125  = GND
  DQ31_B  = M_D_CPU0_SB_DQ<31>
  VSS126  = GND
  G1  = GND
  G2  = GND
  G3  = GND

(kicad_pcb
	(version 20260206)
	(generator "pcbnew")
	(generator_version "10.0")
	(general
		(thickness 1.6)
		(legacy_teardrops no)
	)
	(paper "A4")
	(title_block
		(title "03242023_DA0F0TMBIJ0_F0T_Motherboard_J_brd_V01_OCP.brd")
		(comment 1 "Grand Teton / footprint 652 of 6105 (J8), pads 1-45 of 291")
	)
	(layers
		(0 "F.Cu" signal "TOP")
		(4 "In1.Cu" signal "GND")
		(6 "In2.Cu" signal "IN1")
		(8 "In3.Cu" signal "GND1")
		(10 "In4.Cu" signal "IN2")
		(12 "In5.Cu" signal "GND2")
		(14 "In6.Cu" signal "IN3")
		(16 "In7.Cu" signal "GND3")
		(18 "In8.Cu" signal "VCC")
		(20 "In9.Cu" signal "VCC1")
		(22 "In10.Cu" signal "GND4")
		(24 "In11.Cu" signal "IN4")
		(26 "In12.Cu" signal "GND5")
		(28 "In13.Cu" signal "IN5")
		(30 "In14.Cu" signal "GND6")
		(32 "In15.Cu" signal "IN6")
		(34 "In16.Cu" signal "GND7")
		(2 "B.Cu" signal "BOTTOM")
		(9 "F.Adhes" user "F.Adhesive")
		(11 "B.Adhes" user "B.Adhesive")
		(13 "F.Paste" user "Package Geometry/Pastemask Top")
		(15 "B.Paste" user "Package Geometry/Pastemask Bottom")
		(5 "F.SilkS" user "Ref Des/Silkscreen Top")
		(7 "B.SilkS" user "Ref Des/Silkscreen Bottom")
		(1 "F.Mask" user "Board Geometry/Soldermask Top")
		(3 "B.Mask" user "Board Geometry/Soldermask Bottom")
		(17 "Dwgs.User" user "User.Drawings")
		(19 "Cmts.User" user "User.Comments")
		(21 "Eco1.User" user "User.Eco1")
		(23 "Eco2.User" user "User.Eco2")
		(25 "Edge.Cuts" user "Board Geometry/Outline")
		(27 "Margin" user)
		(31 "F.CrtYd" user "Package Geometry/Place Bound Top")
		(29 "B.CrtYd" user "Package Geometry/Place Bound Bottom")
		(35 "F.Fab" user "Ref Des/Assembly Top")
		(33 "B.Fab" user "Ref Des/Assembly Bottom")
	)
	(footprint ""
		(layer "F.Cu")
		(at 265.674348 -258.091686)
		(property "Reference" "J8"
			(at -3.683 -81.702148 0)
			(unlocked yes)
			(layer "F.SilkS")
			(effects
				(font
					(size 0.7874 0.5842)
					(thickness 0.1524)
				)
				(justify left)
			)
		)
		(property "Value" ""
			(at 0 0 0)
			(layer "F.Fab")
			(effects
				(font
					(size 1.27 1.27)
				)
			)
		)
		(duplicate_pad_numbers_are_jumpers no)
		(pad "1" smd rect
			(at -2.050034 -63.324994 270)
			(size 0.519938 1.4986)
			(layers "F.Cu" "F.Mask" "F.Paste")
			(net "P12V_S3_AUX_CPU0_NVDIMM")
		)
		(pad "2" smd rect
			(at -2.050034 -62.47511 270)
			(size 0.519938 1.4986)
			(layers "F.Cu" "F.Mask" "F.Paste")
			(net "TP_CHD_CPU0_DIMM2_FRU_0")
		)
		(pad "3" smd rect
			(at -2.050034 -61.624972 270)
			(size 0.519938 1.4986)
			(layers "F.Cu" "F.Mask" "F.Paste")
			(net "P3V3_AUX")
		)
		(pad "4" smd rect
			(at -2.050034 -60.775088 270)
			(size 0.519938 1.4986)
			(layers "F.Cu" "F.Mask" "F.Paste")
			(net "I3C_SPD_DDRABCD_CPU0_LVC1_SCL_7")
		)
		(pad "5" smd rect
			(at -2.050034 -59.92495 270)
			(size 0.519938 1.4986)
			(layers "F.Cu" "F.Mask" "F.Paste")
			(net "I3C_SPD_DDRABCD_CPU0_LVC1_SDA")
		)
		(pad "6" smd rect
			(at -2.050034 -59.075066 270)
			(size 0.519938 1.4986)
			(layers "F.Cu" "F.Mask" "F.Paste")
			(net "GND")
		)
		(pad "7" smd rect
			(at -2.050034 -58.224928 270)
			(size 0.519938 1.4986)
			(layers "F.Cu" "F.Mask" "F.Paste")
			(net "M_D_CPU0_SA_DQ<0>")
		)
		(pad "8" smd rect
			(at -2.050034 -57.375044 270)
			(size 0.519938 1.4986)
			(layers "F.Cu" "F.Mask" "F.Paste")
			(net "GND")
		)
		(pad "9" smd rect
			(at -2.050034 -56.524906 270)
			(size 0.519938 1.4986)
			(layers "F.Cu" "F.Mask" "F.Paste")
			(net "M_D_CPU0_SA_DQ<1>")
		)
		(pad "10" smd rect
			(at -2.050034 -55.675022 270)
			(size 0.519938 1.4986)
			(layers "F.Cu" "F.Mask" "F.Paste")
			(net "GND")
		)
		(pad "11" smd rect
			(at -2.050034 -54.824884 270)
			(size 0.519938 1.4986)
			(layers "F.Cu" "F.Mask" "F.Paste")
			(net "M_D_CPU0_SA_DQS_DP<0>")
		)
		(pad "12" smd rect
			(at -2.050034 -53.975 270)
			(size 0.519938 1.4986)
			(layers "F.Cu" "F.Mask" "F.Paste")
			(net "M_D_CPU0_SA_DQS_DN<0>")
		)
		(pad "13" smd rect
			(at -2.050034 -53.125116 270)
			(size 0.519938 1.4986)
			(layers "F.Cu" "F.Mask" "F.Paste")
			(net "GND")
		)
		(pad "14" smd rect
			(at -2.050034 -52.274978 270)
			(size 0.519938 1.4986)
			(layers "F.Cu" "F.Mask" "F.Paste")
			(net "M_D_CPU0_SA_DQ<4>")
		)
		(pad "15" smd rect
			(at -2.050034 -51.425094 270)
			(size 0.519938 1.4986)
			(layers "F.Cu" "F.Mask" "F.Paste")
			(net "GND")
		)
		(pad "16" smd rect
			(at -2.050034 -50.574956 270)
			(size 0.519938 1.4986)
			(layers "F.Cu" "F.Mask" "F.Paste")
			(net "M_D_CPU0_SA_DQ<5>")
		)
		(pad "17" smd rect
			(at -2.050034 -49.725072 270)
			(size 0.519938 1.4986)
			(layers "F.Cu" "F.Mask" "F.Paste")
			(net "GND")
		)
		(pad "18" smd rect
			(at -2.050034 -48.874934 270)
			(size 0.519938 1.4986)
			(layers "F.Cu" "F.Mask" "F.Paste")
			(net "M_D_CPU0_SA_DQ<8>")
		)
		(pad "19" smd rect
			(at -2.050034 -48.02505 270)
			(size 0.519938 1.4986)
			(layers "F.Cu" "F.Mask" "F.Paste")
			(net "GND")
		)
		(pad "20" smd rect
			(at -2.050034 -47.174912 270)
			(size 0.519938 1.4986)
			(layers "F.Cu" "F.Mask" "F.Paste")
			(net "M_D_CPU0_SA_DQ<9>")
		)
		(pad "21" smd rect
			(at -2.050034 -46.325028 270)
			(size 0.519938 1.4986)
			(layers "F.Cu" "F.Mask" "F.Paste")
			(net "GND")
		)
		(pad "22" smd rect
			(at -2.050034 -45.47489 270)
			(size 0.519938 1.4986)
			(layers "F.Cu" "F.Mask" "F.Paste")
			(net "M_D_CPU0_SA_DQS_DP<1>")
		)
		(pad "23" smd rect
			(at -2.050034 -44.625006 270)
			(size 0.519938 1.4986)
			(layers "F.Cu" "F.Mask" "F.Paste")
			(net "M_D_CPU0_SA_DQS_DN<1>")
		)
		(pad "24" smd rect
			(at -2.050034 -43.775122 270)
			(size 0.519938 1.4986)
			(layers "F.Cu" "F.Mask" "F.Paste")
			(net "GND")
		)
		(pad "25" smd rect
			(at -2.050034 -42.924984 270)
			(size 0.519938 1.4986)
			(layers "F.Cu" "F.Mask" "F.Paste")
			(net "M_D_CPU0_SA_DQ<12>")
		)
		(pad "26" smd rect
			(at -2.050034 -42.0751 270)
			(size 0.519938 1.4986)
			(layers "F.Cu" "F.Mask" "F.Paste")
			(net "GND")
		)
		(pad "27" smd rect
			(at -2.050034 -41.224962 270)
			(size 0.519938 1.4986)
			(layers "F.Cu" "F.Mask" "F.Paste")
			(net "M_D_CPU0_SA_DQ<13>")
		)
		(pad "28" smd rect
			(at -2.050034 -40.375078 270)
			(size 0.519938 1.4986)
			(layers "F.Cu" "F.Mask" "F.Paste")
			(net "GND")
		)
		(pad "29" smd rect
			(at -2.050034 -39.52494 270)
			(size 0.519938 1.4986)
			(layers "F.Cu" "F.Mask" "F.Paste")
			(net "M_D_CPU0_SA_DQ<16>")
		)
		(pad "30" smd rect
			(at -2.050034 -38.675056 270)
			(size 0.519938 1.4986)
			(layers "F.Cu" "F.Mask" "F.Paste")
			(net "GND")
		)
		(pad "31" smd rect
			(at -2.050034 -37.824918 270)
			(size 0.519938 1.4986)
			(layers "F.Cu" "F.Mask" "F.Paste")
			(net "M_D_CPU0_SA_DQ<17>")
		)
		(pad "32" smd rect
			(at -2.050034 -36.975034 270)
			(size 0.519938 1.4986)
			(layers "F.Cu" "F.Mask" "F.Paste")
			(net "GND")
		)
		(pad "33" smd rect
			(at -2.050034 -36.124896 270)
			(size 0.519938 1.4986)
			(layers "F.Cu" "F.Mask" "F.Paste")
			(net "M_D_CPU0_SA_DQS_DP<2>")
		)
		(pad "34" smd rect
			(at -2.050034 -35.275012 270)
			(size 0.519938 1.4986)
			(layers "F.Cu" "F.Mask" "F.Paste")
			(net "M_D_CPU0_SA_DQS_DN<2>")
		)
		(pad "35" smd rect
			(at -2.050034 -34.425128 270)
			(size 0.519938 1.4986)
			(layers "F.Cu" "F.Mask" "F.Paste")
			(net "GND")
		)
		(pad "36" smd rect
			(at -2.050034 -33.57499 270)
			(size 0.519938 1.4986)
			(layers "F.Cu" "F.Mask" "F.Paste")
			(net "M_D_CPU0_SA_DQ<20>")
		)
		(pad "37" smd rect
			(at -2.050034 -32.725106 270)
			(size 0.519938 1.4986)
			(layers "F.Cu" "F.Mask" "F.Paste")
			(net "GND")
		)
		(pad "38" smd rect
			(at -2.050034 -31.874968 270)
			(size 0.519938 1.4986)
			(layers "F.Cu" "F.Mask" "F.Paste")
			(net "M_D_CPU0_SA_DQ<21>")
		)
		(pad "39" smd rect
			(at -2.050034 -31.025084 270)
			(size 0.519938 1.4986)
			(layers "F.Cu" "F.Mask" "F.Paste")
			(net "GND")
		)
		(pad "40" smd rect
			(at -2.050034 -30.174946 270)
			(size 0.519938 1.4986)
			(layers "F.Cu" "F.Mask" "F.Paste")
			(net "M_D_CPU0_SA_DQ<24>")
		)
		(pad "41" smd rect
			(at -2.050034 -29.325062 270)
			(size 0.519938 1.4986)
			(layers "F.Cu" "F.Mask" "F.Paste")
			(net "GND")
		)
		(pad "42" smd rect
			(at -2.050034 -28.474924 270)
			(size 0.519938 1.4986)
			(layers "F.Cu" "F.Mask" "F.Paste")
			(net "M_D_CPU0_SA_DQ<25>")
		)
		(pad "43" smd rect
			(at -2.050034 -27.62504 270)
			(size 0.519938 1.4986)
			(layers "F.Cu" "F.Mask" "F.Paste")
			(net "GND")
		)
		(pad "44" smd rect
			(at -2.050034 -26.774902 270)
			(size 0.519938 1.4986)
			(layers "F.Cu" "F.Mask" "F.Paste")
			(net "M_D_CPU0_SA_DQS_DP<3>")
		)
		(pad "45" smd rect
			(at -2.050034 -25.925018 270)
			(size 0.519938 1.4986)
			(layers "F.Cu" "F.Mask" "F.Paste")
			(net "M_D_CPU0_SA_DQS_DN<3>")
		)
	)
)
